# S9S_MB_2U (Grand Teton) — schematic netlist excerpt (pin names and nets, part order shuffled) for the footprints in the layout excerpt that follows; sources: Cadence DE-HDL packaged netlist, KiCad conversion of 03242023_DA0F0TMBIJ0_F0T_Motherboard_J_brd_V01_OCP.brd

H91  HOLE  EMPTY  pkg TH  page 311 : \1\ = GND

U308  74LVC2G07DW7  74LVC2G07DW-7 IC  pkg SOT363_0-65_2X1-25XC  page 246
  \1a\  = PWRGD_P3V3_AUX_PDB_R
  GND  = GND
  \2a\  = NC
  \2y\  = NC
  VCC  = P3V3_AUX
  \1y\  = PWRGD_P3V3_AUX_PDB_BUF_R

R970  Q_RES  240 1% CHIP  pkg 0402LF  page 236 : A = PVNN_TERM_CPU1 ; B = SMB_S3M_CPU1_R_SCL

(kicad_pcb
	(version 20260206)
	(generator "pcbnew")
	(generator_version "10.0")
	(general
		(thickness 1.6)
		(legacy_teardrops no)
	)
	(paper "A4")
	(title_block
		(title "03242023_DA0F0TMBIJ0_F0T_Motherboard_J_brd_V01_OCP.brd")
		(comment 1 "Grand Teton / footprints 1614-1616 of 6105")
	)
	(layers
		(0 "F.Cu" signal "TOP")
		(4 "In1.Cu" signal "GND")
		(6 "In2.Cu" signal "IN1")
		(8 "In3.Cu" signal "GND1")
		(10 "In4.Cu" signal "IN2")
		(12 "In5.Cu" signal "GND2")
		(14 "In6.Cu" signal "IN3")
		(16 "In7.Cu" signal "GND3")
		(18 "In8.Cu" signal "VCC")
		(20 "In9.Cu" signal "VCC1")
		(22 "In10.Cu" signal "GND4")
		(24 "In11.Cu" signal "IN4")
		(26 "In12.Cu" signal "GND5")
		(28 "In13.Cu" signal "IN5")
		(30 "In14.Cu" signal "GND6")
		(32 "In15.Cu" signal "IN6")
		(34 "In16.Cu" signal "GND7")
		(2 "B.Cu" signal "BOTTOM")
		(9 "F.Adhes" user "F.Adhesive")
		(11 "B.Adhes" user "B.Adhesive")
		(13 "F.Paste" user "Package Geometry/Pastemask Top")
		(15 "B.Paste" user "Package Geometry/Pastemask Bottom")
		(5 "F.SilkS" user "Ref Des/Silkscreen Top")
		(7 "B.SilkS" user "Ref Des/Silkscreen Bottom")
		(1 "F.Mask" user "Board Geometry/Soldermask Top")
		(3 "B.Mask" user "Board Geometry/Soldermask Bottom")
		(17 "Dwgs.User" user "User.Drawings")
		(19 "Cmts.User" user "User.Comments")
		(21 "Eco1.User" user "User.Eco1")
		(23 "Eco2.User" user "User.Eco2")
		(25 "Edge.Cuts" user "Board Geometry/Outline")
		(27 "Margin" user)
		(31 "F.CrtYd" user "Package Geometry/Place Bound Top")
		(29 "B.CrtYd" user "Package Geometry/Place Bound Bottom")
		(35 "F.Fab" user "Ref Des/Assembly Top")
		(33 "B.Fab" user "Ref Des/Assembly Bottom")
	)
	(footprint ""
		(layer "F.Cu")
		(at 225.125788 -222.09887)
		(property "Reference" "R970"
			(at 0 0 0)
			(layer "F.SilkS")
			(hide yes)
			(effects
				(font
					(size 1.27 1.27)
				)
			)
		)
		(property "Value" ""
			(at 0 0 0)
			(layer "F.Fab")
			(effects
				(font
					(size 1.27 1.27)
				)
			)
		)
		(duplicate_pad_numbers_are_jumpers no)
		(fp_line
			(start -0.7874 -0.4064)
			(end 0.7874 -0.4064)
			(stroke
				(width 0.1524)
				(type default)
			)
			(layer "F.SilkS")
		)
		(fp_line
			(start -0.7874 0.4064)
			(end -0.7874 -0.4064)
			(stroke
				(width 0.1524)
				(type default)
			)
			(layer "F.SilkS")
		)
		(fp_line
			(start 0.7874 -0.4064)
			(end 0.7874 0.4064)
			(stroke
				(width 0.1524)
				(type default)
			)
			(layer "F.SilkS")
		)
		(fp_line
			(start 0.7874 0.4064)
			(end -0.7874 0.4064)
			(stroke
				(width 0.1524)
				(type default)
			)
			(layer "F.SilkS")
		)
		(fp_line
			(start -0.67945 -0.305054)
			(end -0.12065 -0.305054)
			(stroke
				(width 0.1)
				(type default)
			)
			(layer "F.Fab")
		)
		(fp_line
			(start -0.67945 0.3048)
			(end -0.67945 -0.305054)
			(stroke
				(width 0.1)
				(type default)
			)
			(layer "F.Fab")
		)
		(fp_line
			(start -0.12065 -0.305054)
			(end -0.12065 -0.2794)
			(stroke
				(width 0.1)
				(type default)
			)
			(layer "F.Fab")
		)
		(fp_line
			(start -0.12065 -0.2794)
			(end 0.12065 -0.2794)
			(stroke
				(width 0.1)
				(type default)
			)
			(layer "F.Fab")
		)
		(fp_line
			(start -0.12065 0.2794)
			(end -0.12065 0.3048)
			(stroke
				(width 0.1)
				(type default)
			)
			(layer "F.Fab")
		)
		(fp_line
			(start -0.12065 0.3048)
			(end -0.67945 0.3048)
			(stroke
				(width 0.1)
				(type default)
			)
			(layer "F.Fab")
		)
		(fp_line
			(start 0.120396 0.2794)
			(end -0.12065 0.2794)
			(stroke
				(width 0.1)
				(type default)
			)
			(layer "F.Fab")
		)
		(fp_line
			(start 0.120396 0.3048)
			(end 0.120396 0.2794)
			(stroke
				(width 0.1)
				(type default)
			)
			(layer "F.Fab")
		)
		(fp_line
			(start 0.12065 -0.3048)
			(end 0.67945 -0.3048)
			(stroke
				(width 0.1)
				(type default)
			)
			(layer "F.Fab")
		)
		(fp_line
			(start 0.12065 -0.2794)
			(end 0.12065 -0.3048)
			(stroke
				(width 0.1)
				(type default)
			)
			(layer "F.Fab")
		)
		(fp_line
			(start 0.67945 -0.3048)
			(end 0.67945 0.3048)
			(stroke
				(width 0.1)
				(type default)
			)
			(layer "F.Fab")
		)
		(fp_line
			(start 0.67945 0.3048)
			(end 0.120396 0.3048)
			(stroke
				(width 0.1)
				(type default)
			)
			(layer "F.Fab")
		)
		(pad "1" smd circle
			(at -0.40005 0)
			(size 0 0)
			(layers "F.Cu" "F.Mask" "F.Paste")
			(net "PVNN_TERM_CPU1")
		)
		(pad "2" smd circle
			(at 0.40005 0)
			(size 0 0)
			(layers "F.Cu" "F.Mask" "F.Paste")
			(net "SMB_S3M_CPU1_R_SCL")
		)
	)
	(footprint ""
		(layer "F.Cu")
		(at 307.456078 -422.87317 90)
		(property "Reference" "U308"
			(at -2.590292 -0.651256 0)
			(unlocked yes)
			(layer "F.SilkS")
			(effects
				(font
					(size 0.7874 0.5842)
					(thickness 0.1524)
				)
				(justify left)
			)
		)
		(property "Value" ""
			(at 0 0 90)
			(layer "F.Fab")
			(effects
				(font
					(size 1.27 1.27)
				)
			)
		)
		(duplicate_pad_numbers_are_jumpers no)
		(fp_line
			(start 1.38176 -1.100074)
			(end 0.592074 -1.100074)
			(stroke
				(width 0.1524)
				(type default)
			)
			(layer "F.SilkS")
		)
		(fp_line
			(start 0.592074 -1.100074)
			(end 0 -0.508)
			(stroke
				(width 0.1524)
				(type default)
			)
			(layer "F.SilkS")
		)
		(fp_line
			(start -0.592074 -1.100074)
			(end -1.38176 -1.100074)
			(stroke
				(width 0.1524)
				(type default)
			)
			(layer "F.SilkS")
		)
		(fp_line
			(start -1.38176 -1.100074)
			(end -1.38176 1.100074)
			(stroke
				(width 0.1524)
				(type default)
			)
			(layer "F.SilkS")
		)
		(fp_line
			(start 0 -0.508)
			(end -0.592074 -1.100074)
			(stroke
				(width 0.1524)
				(type default)
			)
			(layer "F.SilkS")
		)
		(fp_line
			(start 1.38176 1.100074)
			(end 1.38176 -1.100074)
			(stroke
				(width 0.1524)
				(type default)
			)
			(layer "F.SilkS")
		)
		(fp_line
			(start -1.38176 1.100074)
			(end 1.38176 1.100074)
			(stroke
				(width 0.1524)
				(type default)
			)
			(layer "F.SilkS")
		)
		(fp_poly
			(pts
				(xy -1.50241 -0.649986) (xy -1.9431 -0.429768) (xy -1.9431 -0.870204)
			)
			(stroke
				(width 0)
				(type default)
			)
			(fill yes)
			(layer "F.SilkS")
		)
		(fp_line
			(start 0.674878 -1.100074)
			(end -0.674878 -1.100074)
			(stroke
				(width 0.1)
				(type default)
			)
			(layer "F.Fab")
		)
		(fp_line
			(start -0.674878 -1.100074)
			(end -0.674878 1.100074)
			(stroke
				(width 0.1)
				(type default)
			)
			(layer "F.Fab")
		)
		(fp_line
			(start 0.674878 1.100074)
			(end 0.674878 -1.100074)
			(stroke
				(width 0.1)
				(type default)
			)
			(layer "F.Fab")
		)
		(fp_line
			(start -0.674878 1.100074)
			(end 0.674878 1.100074)
			(stroke
				(width 0.1)
				(type default)
			)
			(layer "F.Fab")
		)
		(fp_poly
			(pts
				(xy -1.9431 -0.870204) (xy -1.50241 -0.649986) (xy -1.9431 -0.429768)
			)
			(stroke
				(width 0)
				(type default)
			)
			(fill yes)
			(layer "F.Fab")
		)
		(pad "1" smd rect
			(at -0.94996 -0.649986)
			(size 0.4318 0.6096)
			(layers "F.Cu" "F.Mask" "F.Paste")
			(net "PWRGD_P3V3_AUX_PDB_R")
		)
		(pad "2" smd rect
			(at -0.94996 0)
			(size 0.4318 0.6096)
			(layers "F.Cu" "F.Mask" "F.Paste")
			(net "GND")
		)
		(pad "3" smd rect
			(at -0.94996 0.649986)
			(size 0.4318 0.6096)
			(layers "F.Cu" "F.Mask" "F.Paste")
			(net "Net_8600")
		)
		(pad "4" smd rect
			(at 0.94996 0.649986)
			(size 0.4318 0.6096)
			(layers "F.Cu" "F.Mask" "F.Paste")
			(net "Net_8599")
		)
		(pad "5" smd rect
			(at 0.94996 0)
			(size 0.4318 0.6096)
			(layers "F.Cu" "F.Mask" "F.Paste")
			(net "P3V3_AUX")
		)
		(pad "6" smd rect
			(at 0.94996 -0.649986)
			(size 0.4318 0.6096)
			(layers "F.Cu" "F.Mask" "F.Paste")
			(net "PWRGD_P3V3_AUX_PDB_BUF_R")
		)
	)
	(footprint ""
		(layer "F.Cu")
		(at 293.549832 -435.600094)
		(property "Reference" "H91"
			(at -6.814312 -3.983736 0)
			(unlocked yes)
			(layer "F.SilkS")
			(effects
				(font
					(size 0.7874 0.5842)
					(thickness 0.1524)
				)
				(justify left)
			)
		)
		(property "Value" ""
			(at 0 0 0)
			(layer "F.Fab")
			(effects
				(font
					(size 1.27 1.27)
				)
			)
		)
		(duplicate_pad_numbers_are_jumpers no)
		(pad "1" thru_hole circle
			(at 0 0)
			(size 10.0076 10.0076)
			(drill 5.6134)
			(layers "*.Cu" "*.Mask")
			(remove_unused_layers no)
			(net "GND")
			(clearance -1.9431)
		)
	)
)
